(kicad_pcb
	(version 20260206)
	(generator "pcbnew")
	(generator_version "10.0")
	(general
		(thickness 1.6)
		(legacy_teardrops no)
	)
	(paper "A4")
	(title_block
		(title "01162023_DA0F0TEBIF0_F0T_Expander_BD_F_brd_V02_OCP.brd")
		(comment 1 "Grand Teton / footprints 5938-5944 of 9728")
	)
	(layers
		(0 "F.Cu" signal "TOP")
		(4 "In1.Cu" signal "GND")
		(6 "In2.Cu" signal "VCC")
		(8 "In3.Cu" signal "VCC1")
		(10 "In4.Cu" signal "GND1")
		(12 "In5.Cu" signal "IN1")
		(14 "In6.Cu" signal "GND2")
		(16 "In7.Cu" signal "IN2")
		(18 "In8.Cu" signal "GND3")
		(20 "In9.Cu" signal "IN3")
		(22 "In10.Cu" signal "GND4")
		(24 "In11.Cu" signal "IN4")
		(26 "In12.Cu" signal "GND5")
		(28 "In13.Cu" signal "IN5")
		(30 "In14.Cu" signal "GND6")
		(32 "In15.Cu" signal "IN6")
		(34 "In16.Cu" signal "GND7")
		(2 "B.Cu" signal "BOTTOM")
		(9 "F.Adhes" user "F.Adhesive")
		(11 "B.Adhes" user "B.Adhesive")
		(13 "F.Paste" user "Package Geometry/Pastemask Top")
		(15 "B.Paste" user "Package Geometry/Pastemask Bottom")
		(5 "F.SilkS" user "Ref Des/Silkscreen Top")
		(7 "B.SilkS" user "Ref Des/Silkscreen Bottom")
		(1 "F.Mask" user "Board Geometry/Soldermask Top")
		(3 "B.Mask" user "Board Geometry/Soldermask Bottom")
		(17 "Dwgs.User" user "User.Drawings")
		(19 "Cmts.User" user "User.Comments")
		(21 "Eco1.User" user "User.Eco1")
		(23 "Eco2.User" user "User.Eco2")
		(25 "Edge.Cuts" user "Board Geometry/Outline")
		(27 "Margin" user)
		(31 "F.CrtYd" user "Package Geometry/Place Bound Top")
		(29 "B.CrtYd" user "Package Geometry/Place Bound Bottom")
		(35 "F.Fab" user "Ref Des/Assembly Top")
		(33 "B.Fab" user "Ref Des/Assembly Bottom")
	)
	(footprint ""
		(layer "F.Cu")
		(at 17.839944 -70.52437 90)
		(property "Reference" "PC643"
			(at 0 0 90)
			(layer "F.SilkS")
			(hide yes)
			(effects
				(font
					(size 1.27 1.27)
				)
			)
		)
		(property "Value" ""
			(at 0 0 90)
			(layer "F.Fab")
			(effects
				(font
					(size 1.27 1.27)
				)
			)
		)
		(duplicate_pad_numbers_are_jumpers no)
		(fp_line
			(start 1.524 -0.762)
			(end 1.524 0.762)
			(stroke
				(width 0.1524)
				(type default)
			)
			(layer "F.SilkS")
		)
		(fp_line
			(start -1.524 -0.762)
			(end 1.524 -0.762)
			(stroke
				(width 0.1524)
				(type default)
			)
			(layer "F.SilkS")
		)
		(fp_line
			(start 1.524 0.762)
			(end -1.524 0.762)
			(stroke
				(width 0.1524)
				(type default)
			)
			(layer "F.SilkS")
		)
		(fp_line
			(start -1.524 0.762)
			(end -1.524 -0.762)
			(stroke
				(width 0.1524)
				(type default)
			)
			(layer "F.SilkS")
		)
		(fp_line
			(start 1.1049 -0.724916)
			(end -1.1049 -0.724916)
			(stroke
				(width 0.1)
				(type default)
			)
			(layer "F.Fab")
		)
		(fp_line
			(start -1.1049 -0.724916)
			(end -1.1049 0.724916)
			(stroke
				(width 0.1)
				(type default)
			)
			(layer "F.Fab")
		)
		(fp_line
			(start 1.1049 0.724916)
			(end 1.1049 -0.724916)
			(stroke
				(width 0.1)
				(type default)
			)
			(layer "F.Fab")
		)
		(fp_line
			(start -1.1049 0.724916)
			(end 1.1049 0.724916)
			(stroke
				(width 0.1)
				(type default)
			)
			(layer "F.Fab")
		)
		(pad "1" smd rect
			(at -0.889 0 270)
			(size 1.016 1.27)
			(layers "F.Cu" "F.Mask" "F.Paste")
			(net "P12V_SSD0_R")
		)
		(pad "2" smd rect
			(at 0.889 0 270)
			(size 1.016 1.27)
			(layers "F.Cu" "F.Mask" "F.Paste")
			(net "GND")
		)
	)
	(footprint ""
		(layer "F.Cu")
		(at 371.428518 -260.807708 90)
		(property "Reference" "R5802"
			(at 0 0 90)
			(layer "F.SilkS")
			(hide yes)
			(effects
				(font
					(size 1.27 1.27)
				)
			)
		)
		(property "Value" ""
			(at 0 0 90)
			(layer "F.Fab")
			(effects
				(font
					(size 1.27 1.27)
				)
			)
		)
		(duplicate_pad_numbers_are_jumpers no)
		(fp_line
			(start 0.7874 -0.4064)
			(end 0.7874 0.4064)
			(stroke
				(width 0.1524)
				(type default)
			)
			(layer "F.SilkS")
		)
		(fp_line
			(start -0.7874 -0.4064)
			(end 0.7874 -0.4064)
			(stroke
				(width 0.1524)
				(type default)
			)
			(layer "F.SilkS")
		)
		(fp_line
			(start 0.7874 0.4064)
			(end -0.7874 0.4064)
			(stroke
				(width 0.1524)
				(type default)
			)
			(layer "F.SilkS")
		)
		(fp_line
			(start -0.7874 0.4064)
			(end -0.7874 -0.4064)
			(stroke
				(width 0.1524)
				(type default)
			)
			(layer "F.SilkS")
		)
		(fp_line
			(start -0.12065 -0.305054)
			(end -0.12065 -0.2794)
			(stroke
				(width 0.1)
				(type default)
			)
			(layer "F.Fab")
		)
		(fp_line
			(start -0.67945 -0.305054)
			(end -0.12065 -0.305054)
			(stroke
				(width 0.1)
				(type default)
			)
			(layer "F.Fab")
		)
		(fp_line
			(start 0.67945 -0.3048)
			(end 0.67945 0.3048)
			(stroke
				(width 0.1)
				(type default)
			)
			(layer "F.Fab")
		)
		(fp_line
			(start 0.12065 -0.3048)
			(end 0.67945 -0.3048)
			(stroke
				(width 0.1)
				(type default)
			)
			(layer "F.Fab")
		)
		(fp_line
			(start 0.12065 -0.2794)
			(end 0.12065 -0.3048)
			(stroke
				(width 0.1)
				(type default)
			)
			(layer "F.Fab")
		)
		(fp_line
			(start -0.12065 -0.2794)
			(end 0.12065 -0.2794)
			(stroke
				(width 0.1)
				(type default)
			)
			(layer "F.Fab")
		)
		(fp_line
			(start 0.120396 0.2794)
			(end -0.12065 0.2794)
			(stroke
				(width 0.1)
				(type default)
			)
			(layer "F.Fab")
		)
		(fp_line
			(start -0.12065 0.2794)
			(end -0.12065 0.3048)
			(stroke
				(width 0.1)
				(type default)
			)
			(layer "F.Fab")
		)
		(fp_line
			(start 0.67945 0.3048)
			(end 0.120396 0.3048)
			(stroke
				(width 0.1)
				(type default)
			)
			(layer "F.Fab")
		)
		(fp_line
			(start 0.120396 0.3048)
			(end 0.120396 0.2794)
			(stroke
				(width 0.1)
				(type default)
			)
			(layer "F.Fab")
		)
		(fp_line
			(start -0.12065 0.3048)
			(end -0.67945 0.3048)
			(stroke
				(width 0.1)
				(type default)
			)
			(layer "F.Fab")
		)
		(fp_line
			(start -0.67945 0.3048)
			(end -0.67945 -0.305054)
			(stroke
				(width 0.1)
				(type default)
			)
			(layer "F.Fab")
		)
		(pad "1" smd circle
			(at -0.40005 0 90)
			(size 0 0)
			(layers "F.Cu" "F.Mask" "F.Paste")
			(net "PEX3_SYS_ERR_N_G")
		)
		(pad "2" smd circle
			(at 0.40005 0 90)
			(size 0 0)
			(layers "F.Cu" "F.Mask" "F.Paste")
			(net "PEX3_SYS_ERR_FPGA")
		)
	)
	(footprint ""
		(layer "F.Cu")
		(at 145.749772 -270.89989)
		(property "Reference" "H89"
			(at -9.468358 5.423154 0)
			(unlocked yes)
			(layer "F.SilkS")
			(effects
				(font
					(size 0.7874 0.5842)
					(thickness 0.1524)
				)
				(justify left)
			)
		)
		(property "Value" ""
			(at 0 0 0)
			(layer "F.Fab")
			(effects
				(font
					(size 1.27 1.27)
				)
			)
		)
		(duplicate_pad_numbers_are_jumpers no)
		(fp_arc
			(start -5.917438 -5.383022)
			(mid -0.133593 -7.998818)
			(end 5.734558 -5.578094)
			(stroke
				(width 0.1524)
				(type default)
			)
			(layer "F.SilkS")
		)
		(fp_arc
			(start 7.987284 -0.45212)
			(mid 7.996831 -0.22615)
			(end 7.999984 0)
			(stroke
				(width 0.1524)
				(type default)
			)
			(layer "F.SilkS")
		)
		(fp_arc
			(start 7.999984 0)
			(mid -0.877926 7.950904)
			(end -7.806436 -1.745996)
			(stroke
				(width 0.1524)
				(type default)
			)
			(layer "F.SilkS")
		)
		(fp_arc
			(start -6.001004 -5.290312)
			(mid -4.324075 -6.730651)
			(end -2.316988 -7.657084)
			(stroke
				(width 0.1524)
				(type default)
			)
			(layer "B.SilkS")
		)
		(fp_arc
			(start 1.529588 -7.85241)
			(mid 4.016762 -6.91843)
			(end 6.060948 -5.221478)
			(stroke
				(width 0.1524)
				(type default)
			)
			(layer "B.SilkS")
		)
		(fp_arc
			(start 7.813802 -1.71577)
			(mid 7.953308 -0.862922)
			(end 7.999984 0)
			(stroke
				(width 0.1524)
				(type default)
			)
			(layer "B.SilkS")
		)
		(fp_arc
			(start 7.999984 0)
			(mid 0.524857 7.982789)
			(end -7.93115 1.047496)
			(stroke
				(width 0.1524)
				(type default)
			)
			(layer "B.SilkS")
		)
		(fp_circle
			(center 0 0)
			(end 7.999984 0)
			(stroke
				(width 0.1)
				(type default)
			)
			(fill no)
			(layer "B.Fab")
		)
		(fp_circle
			(center 0 0)
			(end 7.999984 0)
			(stroke
				(width 0.1)
				(type default)
			)
			(fill no)
			(layer "F.Fab")
		)
		(pad "" np_thru_hole circle
			(at 0 0)
			(size 4.5212 4.5212)
			(drill 4.5212)
			(layers "*.Cu" "*.Mask")
			(clearance 0.381)
			(thermal_gap 0.381)
		)
		(pad "2" thru_hole circle
			(at 3.6322 0)
			(size 0.762 0.762)
			(drill 0.5588)
			(layers "*.Cu" "*.Mask")
			(remove_unused_layers no)
			(net "GND")
			(clearance 0.1524)
			(thermal_gap 0.1524)
		)
		(pad "3" thru_hole circle
			(at 2.568448 -2.568448)
			(size 0.762 0.762)
			(drill 0.5588)
			(layers "*.Cu" "*.Mask")
			(remove_unused_layers no)
			(net "GND")
			(clearance 0.1524)
			(thermal_gap 0.1524)
		)
		(pad "4" thru_hole circle
			(at 0 -3.6322)
			(size 0.762 0.762)
			(drill 0.5588)
			(layers "*.Cu" "*.Mask")
			(remove_unused_layers no)
			(net "GND")
			(clearance 0.1524)
			(thermal_gap 0.1524)
		)
		(pad "5" thru_hole circle
			(at -2.568448 -2.568448)
			(size 0.762 0.762)
			(drill 0.5588)
			(layers "*.Cu" "*.Mask")
			(remove_unused_layers no)
			(net "GND")
			(clearance 0.1524)
			(thermal_gap 0.1524)
		)
		(pad "6" thru_hole circle
			(at -3.6322 0)
			(size 0.762 0.762)
			(drill 0.5588)
			(layers "*.Cu" "*.Mask")
			(remove_unused_layers no)
			(net "GND")
			(clearance 0.1524)
			(thermal_gap 0.1524)
		)
		(pad "7" thru_hole circle
			(at -2.568448 2.568448)
			(size 0.762 0.762)
			(drill 0.5588)
			(layers "*.Cu" "*.Mask")
			(remove_unused_layers no)
			(net "GND")
			(clearance 0.1524)
			(thermal_gap 0.1524)
		)
		(pad "8" thru_hole circle
			(at 0 3.6322)
			(size 0.762 0.762)
			(drill 0.5588)
			(layers "*.Cu" "*.Mask")
			(remove_unused_layers no)
			(net "GND")
			(clearance 0.1524)
			(thermal_gap 0.1524)
		)
		(pad "9" thru_hole circle
			(at 2.568448 2.568448)
			(size 0.762 0.762)
			(drill 0.5588)
			(layers "*.Cu" "*.Mask")
			(remove_unused_layers no)
			(net "GND")
			(clearance 0.1524)
			(thermal_gap 0.1524)
		)
		(zone
			(layer "F.Cu")
			(hatch none 0.5)
			(connect_pads
				(clearance 0)
			)
			(min_thickness 0.25)
			(keepout
				(tracks not_allowed)
				(vias allowed)
				(pads allowed)
				(copperpour not_allowed)
				(footprints allowed)
			)
			(placement
				(enabled no)
				(sheetname "")
			)
			(fill
				(thermal_gap 0.5)
				(thermal_bridge_width 0.5)
				(island_removal_mode 0)
			)
			(polygon
				(pts
					(arc
						(start 145.749772 -262.899906)
						(mid 137.749788 -270.89989)
						(end 145.749772 -278.899874)
					)
					(arc
						(start 145.749772 -275.64969)
						(mid 140.999972 -270.89989)
						(end 145.749772 -266.15009)
					)
				)
			)
		)
		(zone
			(layer "F.Cu")
			(hatch none 0.5)
			(connect_pads
				(clearance 0)
			)
			(min_thickness 0.25)
			(keepout
				(tracks not_allowed)
				(vias allowed)
				(pads allowed)
				(copperpour not_allowed)
				(footprints allowed)
			)
			(placement
				(enabled no)
				(sheetname "")
			)
			(fill
				(thermal_gap 0.5)
				(thermal_bridge_width 0.5)
				(island_removal_mode 0)
			)
			(polygon
				(pts
					(arc
						(start 145.749772 -262.899906)
						(mid 153.749756 -270.89989)
						(end 145.749772 -278.899874)
					)
					(arc
						(start 145.749772 -275.64969)
						(mid 150.499572 -270.89989)
						(end 145.749772 -266.15009)
					)
				)
			)
		)
		(zone
			(layers "F.Cu" "B.Cu" "In1.Cu" "In2.Cu" "In3.Cu" "In4.Cu" "In5.Cu" "In6.Cu"
				"In7.Cu" "In8.Cu" "In9.Cu" "In10.Cu" "In11.Cu" "In12.Cu" "In13.Cu" "In14.Cu"
				"In15.Cu" "In16.Cu"
			)
			(hatch none 0.5)
			(connect_pads
				(clearance 0)
			)
			(min_thickness 0.25)
			(keepout
				(tracks not_allowed)
				(vias allowed)
				(pads allowed)
				(copperpour not_allowed)
				(footprints allowed)
			)
			(placement
				(enabled no)
				(sheetname "")
			)
			(fill
				(thermal_gap 0.5)
				(thermal_bridge_width 0.5)
				(island_removal_mode 0)
			)
			(polygon
				(pts
					(arc
						(start 148.515832 -270.89989)
						(mid 142.983712 -270.89989)
						(end 148.515832 -270.89989)
					)
				)
			)
		)
		(zone
			(layer "B.Cu")
			(hatch none 0.5)
			(connect_pads
				(clearance 0)
			)
			(min_thickness 0.25)
			(keepout
				(tracks not_allowed)
				(vias allowed)
				(pads allowed)
				(copperpour not_allowed)
				(footprints allowed)
			)
			(placement
				(enabled no)
				(sheetname "")
			)
			(fill
				(thermal_gap 0.5)
				(thermal_bridge_width 0.5)
				(island_removal_mode 0)
			)
			(polygon
				(pts
					(arc
						(start 145.749772 -265.89609)
						(mid 140.745972 -270.89989)
						(end 145.749772 -275.90369)
					)
					(arc
						(start 145.749772 -275.42109)
						(mid 141.228572 -270.89989)
						(end 145.749772 -266.37869)
					)
				)
			)
		)
		(zone
			(layer "B.Cu")
			(hatch none 0.5)
			(connect_pads
				(clearance 0)
			)
			(min_thickness 0.25)
			(keepout
				(tracks not_allowed)
				(vias allowed)
				(pads allowed)
				(copperpour not_allowed)
				(footprints allowed)
			)
			(placement
				(enabled no)
				(sheetname "")
			)
			(fill
				(thermal_gap 0.5)
				(thermal_bridge_width 0.5)
				(island_removal_mode 0)
			)
			(polygon
				(pts
					(arc
						(start 145.749772 -265.89609)
						(mid 150.753572 -270.89989)
						(end 145.749772 -275.90369)
					)
					(arc
						(start 145.749772 -275.42109)
						(mid 150.270972 -270.89989)
						(end 145.749772 -266.37869)
					)
				)
			)
		)
	)
	(footprint ""
		(layer "F.Cu")
		(at 403.455124 -53.468524 90)
		(property "Reference" "PC569"
			(at 0 0 90)
			(layer "F.SilkS")
			(hide yes)
			(effects
				(font
					(size 1.27 1.27)
				)
			)
		)
		(property "Value" ""
			(at 0 0 90)
			(layer "F.Fab")
			(effects
				(font
					(size 1.27 1.27)
				)
			)
		)
		(duplicate_pad_numbers_are_jumpers no)
		(fp_line
			(start 1.524 -0.762)
			(end 1.524 0.762)
			(stroke
				(width 0.1524)
				(type default)
			)
			(layer "F.SilkS")
		)
		(fp_line
			(start -1.524 -0.762)
			(end 1.524 -0.762)
			(stroke
				(width 0.1524)
				(type default)
			)
			(layer "F.SilkS")
		)
		(fp_line
			(start 1.524 0.762)
			(end -1.524 0.762)
			(stroke
				(width 0.1524)
				(type default)
			)
			(layer "F.SilkS")
		)
		(fp_line
			(start -1.524 0.762)
			(end -1.524 -0.762)
			(stroke
				(width 0.1524)
				(type default)
			)
			(layer "F.SilkS")
		)
		(fp_line
			(start 1.1049 -0.724916)
			(end -1.1049 -0.724916)
			(stroke
				(width 0.1)
				(type default)
			)
			(layer "F.Fab")
		)
		(fp_line
			(start -1.1049 -0.724916)
			(end -1.1049 0.724916)
			(stroke
				(width 0.1)
				(type default)
			)
			(layer "F.Fab")
		)
		(fp_line
			(start 1.1049 0.724916)
			(end 1.1049 -0.724916)
			(stroke
				(width 0.1)
				(type default)
			)
			(layer "F.Fab")
		)
		(fp_line
			(start -1.1049 0.724916)
			(end 1.1049 0.724916)
			(stroke
				(width 0.1)
				(type default)
			)
			(layer "F.Fab")
		)
		(pad "1" smd rect
			(at -0.889 0 270)
			(size 1.016 1.27)
			(layers "F.Cu" "F.Mask" "F.Paste")
			(net "GND")
		)
		(pad "2" smd rect
			(at 0.889 0 270)
			(size 1.016 1.27)
			(layers "F.Cu" "F.Mask" "F.Paste")
			(net "P3V3_AUX")
		)
	)
	(footprint ""
		(layer "F.Cu")
		(at 293.657782 -356.244906 90)
		(property "Reference" "C2366"
			(at 0 0 90)
			(layer "F.SilkS")
			(hide yes)
			(effects
				(font
					(size 1.27 1.27)
				)
			)
		)
		(property "Value" ""
			(at 0 0 90)
			(layer "F.Fab")
			(effects
				(font
					(size 1.27 1.27)
				)
			)
		)
		(duplicate_pad_numbers_are_jumpers no)
		(fp_line
			(start 0.299974 -0.150114)
			(end 0.299974 0.150114)
			(stroke
				(width 0.1)
				(type default)
			)
			(layer "F.Fab")
		)
		(fp_line
			(start -0.299974 -0.150114)
			(end 0.299974 -0.150114)
			(stroke
				(width 0.1)
				(type default)
			)
			(layer "F.Fab")
		)
		(fp_line
			(start 0.299974 0.150114)
			(end -0.299974 0.150114)
			(stroke
				(width 0.1)
				(type default)
			)
			(layer "F.Fab")
		)
		(fp_line
			(start -0.299974 0.150114)
			(end -0.299974 -0.150114)
			(stroke
				(width 0.1)
				(type default)
			)
			(layer "F.Fab")
		)
		(pad "1" smd rect
			(at -0.2667 0 90)
			(size 0.3048 0.381)
			(layers "F.Cu" "F.Mask" "F.Paste")
			(net "P5E_PEX2_STN4_TX_DN<67>")
		)
		(pad "2" smd rect
			(at 0.2667 0 90)
			(size 0.3048 0.381)
			(layers "F.Cu" "F.Mask" "F.Paste")
			(net "P5E_PEX2_STN4_TX_C_DN<67>")
		)
	)
	(footprint ""
		(layer "F.Cu")
		(at 70.673722 -350.098614 90)
		(property "Reference" "C137"
			(at 0 0 90)
			(layer "F.SilkS")
			(hide yes)
			(effects
				(font
					(size 1.27 1.27)
				)
			)
		)
		(property "Value" ""
			(at 0 0 90)
			(layer "F.Fab")
			(effects
				(font
					(size 1.27 1.27)
				)
			)
		)
		(duplicate_pad_numbers_are_jumpers no)
		(fp_line
			(start 0.299974 -0.150114)
			(end 0.299974 0.150114)
			(stroke
				(width 0.1)
				(type default)
			)
			(layer "F.Fab")
		)
		(fp_line
			(start -0.299974 -0.150114)
			(end 0.299974 -0.150114)
			(stroke
				(width 0.1)
				(type default)
			)
			(layer "F.Fab")
		)
		(fp_line
			(start 0.299974 0.150114)
			(end -0.299974 0.150114)
			(stroke
				(width 0.1)
				(type default)
			)
			(layer "F.Fab")
		)
		(fp_line
			(start -0.299974 0.150114)
			(end -0.299974 -0.150114)
			(stroke
				(width 0.1)
				(type default)
			)
			(layer "F.Fab")
		)
		(pad "1" smd rect
			(at -0.2667 0 90)
			(size 0.3048 0.381)
			(layers "F.Cu" "F.Mask" "F.Paste")
			(net "P5E_PEX0_STN6_TX_DP<107>")
		)
		(pad "2" smd rect
			(at 0.2667 0 90)
			(size 0.3048 0.381)
			(layers "F.Cu" "F.Mask" "F.Paste")
			(net "P5E_PEX0_STN6_TX_C_DP<107>")
		)
	)
	(footprint ""
		(layer "F.Cu")
		(at 149.387814 -294.819832)
		(property "Reference" "C3201"
			(at 0 0 0)
			(layer "F.SilkS")
			(hide yes)
			(effects
				(font
					(size 1.27 1.27)
				)
			)
		)
		(property "Value" ""
			(at 0 0 0)
			(layer "F.Fab")
			(effects
				(font
					(size 1.27 1.27)
				)
			)
		)
		(duplicate_pad_numbers_are_jumpers no)
		(fp_line
			(start -1.2954 -0.5842)
			(end 1.2954 -0.5842)
			(stroke
				(width 0.1524)
				(type default)
			)
			(layer "F.SilkS")
		)
		(fp_line
			(start -1.2954 0.5842)
			(end -1.2954 -0.5842)
			(stroke
				(width 0.1524)
				(type default)
			)
			(layer "F.SilkS")
		)
		(fp_line
			(start 1.2954 -0.5842)
			(end 1.2954 0.5842)
			(stroke
				(width 0.1524)
				(type default)
			)
			(layer "F.SilkS")
		)
		(fp_line
			(start 1.2954 0.5842)
			(end -1.2954 0.5842)
			(stroke
				(width 0.1524)
				(type default)
			)
			(layer "F.SilkS")
		)
		(fp_line
			(start -1.1938 -0.4064)
			(end -0.8636 -0.4064)
			(stroke
				(width 0.1)
				(type default)
			)
			(layer "F.Fab")
		)
		(fp_line
			(start -1.1938 0.4064)
			(end -1.1938 -0.4064)
			(stroke
				(width 0.1)
				(type default)
			)
			(layer "F.Fab")
		)
		(fp_line
			(start -0.8636 -0.4572)
			(end 0.8636 -0.4572)
			(stroke
				(width 0.1)
				(type default)
			)
			(layer "F.Fab")
		)
		(fp_line
			(start -0.8636 -0.4064)
			(end -0.8636 -0.4572)
			(stroke
				(width 0.1)
				(type default)
			)
			(layer "F.Fab")
		)
		(fp_line
			(start -0.8636 0.4064)
			(end -1.1938 0.4064)
			(stroke
				(width 0.1)
				(type default)
			)
			(layer "F.Fab")
		)
		(fp_line
			(start -0.8636 0.4572)
			(end -0.8636 0.4064)
			(stroke
				(width 0.1)
				(type default)
			)
			(layer "F.Fab")
		)
		(fp_line
			(start 0.8636 -0.4572)
			(end 0.8636 -0.4064)
			(stroke
				(width 0.1)
				(type default)
			)
			(layer "F.Fab")
		)
		(fp_line
			(start 0.8636 -0.4064)
			(end 1.1938 -0.4064)
			(stroke
				(width 0.1)
				(type default)
			)
			(layer "F.Fab")
		)
		(fp_line
			(start 0.8636 0.4064)
			(end 0.8636 0.4572)
			(stroke
				(width 0.1)
				(type default)
			)
			(layer "F.Fab")
		)
		(fp_line
			(start 0.8636 0.4572)
			(end -0.8636 0.4572)
			(stroke
				(width 0.1)
				(type default)
			)
			(layer "F.Fab")
		)
		(fp_line
			(start 1.1938 -0.4064)
			(end 1.1938 0.4064)
			(stroke
				(width 0.1)
				(type default)
			)
			(layer "F.Fab")
		)
		(fp_line
			(start 1.1938 0.4064)
			(end 0.8636 0.4064)
			(stroke
				(width 0.1)
				(type default)
			)
			(layer "F.Fab")
		)
		(pad "1" smd rect
			(at -0.7366 0 270)
			(size 0.7112 0.8128)
			(layers "F.Cu" "F.Mask" "F.Paste")
			(net "PCEPLL2_VDDA18_PEX1")
		)
		(pad "2" smd rect
			(at 0.7366 0 270)
			(size 0.7112 0.8128)
			(layers "F.Cu" "F.Mask" "F.Paste")
			(net "GND")
		)
	)
)
